# BASEBOARD_FAB2 (Tioga Pass) — schematic netlist excerpt (pin names and nets, part order shuffled) for the footprints in the layout excerpt that follows; sources: Cadence DE-HDL packaged netlist, KiCad conversion of Wiwynn_Tioga_Pass_MB.brd

R25W37  120R2F-GP  1%  pkg RCL_GP  page 151 : \1\ = BMC_M_BG0 ; \2\ = P1V2_AUX_BMC
R7D19  RES  1.00K 1% EMPTY  pkg 0402  page 126 : A = FM_OC_DETECT_EN_N ; B = GND
C4D20  CAP_A  0.1UF 16V 10% X7R  pkg 0402V  page 201 : A = VR_PVCCIN_CPU0_AVINSEN ; B = GND

(kicad_pcb
	(version 20260206)
	(generator "pcbnew")
	(generator_version "10.0")
	(general
		(thickness 1.6)
		(legacy_teardrops no)
	)
	(paper "A4")
	(title_block
		(title "Wiwynn_Tioga_Pass_MB.brd")
		(comment 1 "Tioga Pass / footprints 1597-1599 of 4770")
	)
	(layers
		(0 "F.Cu" signal "TOP")
		(4 "In1.Cu" signal "L2GND")
		(6 "In2.Cu" signal "L3")
		(8 "In3.Cu" signal "L4GND")
		(10 "In4.Cu" signal "L5")
		(12 "In5.Cu" signal "L6GND")
		(14 "In6.Cu" signal "L7VCC")
		(16 "In7.Cu" signal "L8VCC")
		(18 "In8.Cu" signal "L9GND")
		(20 "In9.Cu" signal "L10")
		(22 "In10.Cu" signal "L11GND")
		(24 "In11.Cu" signal "L12")
		(26 "In12.Cu" signal "L13GND")
		(2 "B.Cu" signal "BOTTOM")
		(9 "F.Adhes" user "F.Adhesive")
		(11 "B.Adhes" user "B.Adhesive")
		(13 "F.Paste" user "Package Geometry/Pastemask Top")
		(15 "B.Paste" user "Package Geometry/Pastemask Bottom")
		(5 "F.SilkS" user "Ref Des/Silkscreen Top")
		(7 "B.SilkS" user "Ref Des/Silkscreen Bottom")
		(1 "F.Mask" user "Board Geometry/Soldermask Top")
		(3 "B.Mask" user "Board Geometry/Soldermask Bottom")
		(17 "Dwgs.User" user "User.Drawings")
		(19 "Cmts.User" user "User.Comments")
		(21 "Eco1.User" user "User.Eco1")
		(23 "Eco2.User" user "User.Eco2")
		(25 "Edge.Cuts" user "Board Geometry/Outline")
		(27 "Margin" user)
		(31 "F.CrtYd" user "Package Geometry/Place Bound Top")
		(29 "B.CrtYd" user "Package Geometry/Place Bound Bottom")
		(35 "F.Fab" user "Ref Des/Assembly Top")
		(33 "B.Fab" user "Ref Des/Assembly Bottom")
	)
	(footprint ""
		(layer "F.Cu")
		(at 393.103354 -86.295484)
		(property "Reference" "R7D19"
			(at 0 0 0)
			(layer "F.SilkS")
			(hide yes)
			(effects
				(font
					(size 1.27 1.27)
				)
			)
		)
		(property "Value" ""
			(at 0 0 0)
			(layer "F.Fab")
			(effects
				(font
					(size 1.27 1.27)
				)
			)
		)
		(duplicate_pad_numbers_are_jumpers no)
		(fp_poly
			(pts
				(xy -0.2794 -0.1016) (xy 0.2794 -0.1016) (xy 0.2794 0.9906) (xy -0.2794 0.9906)
			)
			(stroke
				(width 0)
				(type default)
			)
			(fill no)
			(layer "F.CrtYd")
		)
		(fp_line
			(start -0.2794 -0.1016)
			(end -0.2794 0.9906)
			(stroke
				(width 0.1)
				(type default)
			)
			(layer "F.Fab")
		)
		(fp_line
			(start -0.2794 0.9906)
			(end 0.2794 0.9906)
			(stroke
				(width 0.1)
				(type default)
			)
			(layer "F.Fab")
		)
		(fp_line
			(start 0.2794 -0.1016)
			(end -0.2794 -0.1016)
			(stroke
				(width 0.1)
				(type default)
			)
			(layer "F.Fab")
		)
		(fp_line
			(start 0.2794 0.9906)
			(end 0.2794 -0.1016)
			(stroke
				(width 0.1)
				(type default)
			)
			(layer "F.Fab")
		)
		(pad "1" smd rect
			(at 0 0)
			(size 0.508 0.508)
			(layers "F.Cu" "F.Mask" "F.Paste")
			(net "FM_OC_DETECT_EN_N")
		)
		(pad "2" smd rect
			(at 0 0.889)
			(size 0.508 0.508)
			(layers "F.Cu" "F.Mask" "F.Paste")
			(net "GND")
		)
		(zone
			(layer "F.Cu")
			(hatch none 0.5)
			(connect_pads
				(clearance 0)
			)
			(min_thickness 0.25)
			(keepout
				(tracks allowed)
				(vias not_allowed)
				(pads allowed)
				(copperpour not_allowed)
				(footprints allowed)
			)
			(placement
				(enabled no)
				(sheetname "")
			)
			(fill
				(thermal_gap 0.5)
				(thermal_bridge_width 0.5)
				(island_removal_mode 0)
			)
			(polygon
				(pts
					(xy 392.849354 -86.041484) (xy 393.357354 -86.041484) (xy 393.357354 -85.660484) (xy 392.849354 -85.660484)
				)
			)
		)
		(zone
			(layer "F.Cu")
			(hatch none 0.5)
			(connect_pads
				(clearance 0)
			)
			(min_thickness 0.25)
			(keepout
				(tracks not_allowed)
				(vias allowed)
				(pads allowed)
				(copperpour not_allowed)
				(footprints allowed)
			)
			(placement
				(enabled no)
				(sheetname "")
			)
			(fill
				(thermal_gap 0.5)
				(thermal_bridge_width 0.5)
				(island_removal_mode 0)
			)
			(polygon
				(pts
					(xy 392.849354 -85.660484) (xy 393.357354 -85.660484) (xy 393.357354 -86.041484) (xy 392.849354 -86.041484)
				)
			)
		)
	)
	(footprint ""
		(layer "F.Cu")
		(at 183.0832 -75.565 -90)
		(property "Reference" "C4D20"
			(at 0 0 270)
			(layer "F.SilkS")
			(hide yes)
			(effects
				(font
					(size 1.27 1.27)
				)
			)
		)
		(property "Value" ""
			(at 0 0 270)
			(layer "F.Fab")
			(effects
				(font
					(size 1.27 1.27)
				)
			)
		)
		(duplicate_pad_numbers_are_jumpers no)
		(fp_rect
			(start 0.3048 0.9906)
			(end -0.3048 -0.1016)
			(stroke
				(width 0)
				(type default)
			)
			(fill no)
			(layer "F.CrtYd")
		)
		(fp_line
			(start -0.3048 0.9906)
			(end 0.3048 0.9906)
			(stroke
				(width 0.1)
				(type default)
			)
			(layer "F.Fab")
		)
		(fp_line
			(start 0.3048 0.9906)
			(end 0.3048 -0.1016)
			(stroke
				(width 0.1)
				(type default)
			)
			(layer "F.Fab")
		)
		(fp_line
			(start -0.3048 -0.1016)
			(end -0.3048 0.9906)
			(stroke
				(width 0.1)
				(type default)
			)
			(layer "F.Fab")
		)
		(fp_line
			(start 0.3048 -0.1016)
			(end -0.3048 -0.1016)
			(stroke
				(width 0.1)
				(type default)
			)
			(layer "F.Fab")
		)
		(pad "1" smd rect
			(at 0 0 270)
			(size 0.508 0.508)
			(layers "F.Cu" "F.Mask" "F.Paste")
			(net "VR_PVCCIN_CPU0_AVINSEN")
		)
		(pad "2" smd rect
			(at 0 0.889 270)
			(size 0.508 0.508)
			(layers "F.Cu" "F.Mask" "F.Paste")
			(net "GND")
		)
		(zone
			(layer "F.Cu")
			(hatch none 0.5)
			(connect_pads
				(clearance 0)
			)
			(min_thickness 0.25)
			(keepout
				(tracks allowed)
				(vias not_allowed)
				(pads allowed)
				(copperpour not_allowed)
				(footprints allowed)
			)
			(placement
				(enabled no)
				(sheetname "")
			)
			(fill
				(thermal_gap 0.5)
				(thermal_bridge_width 0.5)
				(island_removal_mode 0)
			)
			(polygon
				(pts
					(xy 182.4482 -75.311) (xy 182.8292 -75.311) (xy 182.8292 -75.819) (xy 182.4482 -75.819)
				)
			)
		)
		(zone
			(layer "F.Cu")
			(hatch none 0.5)
			(connect_pads
				(clearance 0)
			)
			(min_thickness 0.25)
			(keepout
				(tracks not_allowed)
				(vias allowed)
				(pads allowed)
				(copperpour not_allowed)
				(footprints allowed)
			)
			(placement
				(enabled no)
				(sheetname "")
			)
			(fill
				(thermal_gap 0.5)
				(thermal_bridge_width 0.5)
				(island_removal_mode 0)
			)
			(polygon
				(pts
					(xy 182.4482 -75.311) (xy 182.8292 -75.311) (xy 182.8292 -75.819) (xy 182.4482 -75.819)
				)
			)
		)
	)
	(footprint ""
		(layer "F.Cu")
		(at 451.85838 -33.5915 90)
		(property "Reference" "R25W37"
			(at 0 0 90)
			(layer "F.SilkS")
			(hide yes)
			(effects
				(font
					(size 1.27 1.27)
				)
			)
		)
		(property "Value" "*"
			(at 0.064008 -4.108196 90)
			(unlocked yes)
			(layer "F.Fab")
			(hide yes)
			(effects
				(font
					(size 1.27 1.016)
					(thickness 0.1524)
				)
			)
		)
		(property "Device Type" "120R2F-GP_RCL_GP-120R2F-GP,64.A"
			(at 0.064008 -5.632196 90)
			(unlocked yes)
			(layer "F.Fab")
			(hide yes)
			(effects
				(font
					(size 1.27 1.016)
					(thickness 0.1524)
				)
			)
		)
		(duplicate_pad_numbers_are_jumpers no)
		(fp_line
			(start 0.508 -0.9398)
			(end -0.508 -0.9398)
			(stroke
				(width 0.1524)
				(type default)
			)
			(layer "F.SilkS")
		)
		(fp_line
			(start -0.508 -0.9398)
			(end -0.508 0.9398)
			(stroke
				(width 0.1524)
				(type default)
			)
			(layer "F.SilkS")
		)
		(fp_rect
			(start -0.508 0.9398)
			(end 0.508 -0.9398)
			(stroke
				(width 0)
				(type default)
			)
			(fill no)
			(layer "F.CrtYd")
		)
		(fp_rect
			(start -0.508 0.9398)
			(end 0.508 -0.9398)
			(stroke
				(width 0)
				(type default)
			)
			(fill no)
			(layer "F.Fab")
		)
		(pad "1" smd custom
			(at 0 -0.4445 90)
			(size 0.1397 0.1397)
			(layers "F.Cu" "F.Mask" "F.Paste")
			(net "BMC_M_BG0")
			(options
				(clearance outline)
				(anchor circle)
			)
			(primitives
				(gr_poly
					(pts
						(arc
							(start -0.1778 -0.2794)
							(mid -0.249642 -0.249642)
							(end -0.2794 -0.1778)
						)
						(arc
							(start -0.2794 0.1778)
							(mid -0.249642 0.249642)
							(end -0.1778 0.2794)
						)
						(arc
							(start 0.1778 0.2794)
							(mid 0.249642 0.249642)
							(end 0.2794 0.1778)
						)
						(arc
							(start 0.2794 -0.1778)
							(mid 0.249642 -0.249642)
							(end 0.1778 -0.2794)
						)
					)
					(width 0)
					(fill yes)
				)
			)
		)
		(pad "2" smd custom
			(at 0 0.4445 90)
			(size 0.1397 0.1397)
			(layers "F.Cu" "F.Mask" "F.Paste")
			(net "P1V2_AUX_BMC")
			(options
				(clearance outline)
				(anchor circle)
			)
			(primitives
				(gr_poly
					(pts
						(arc
							(start -0.1778 -0.2794)
							(mid -0.249642 -0.249642)
							(end -0.2794 -0.1778)
						)
						(arc
							(start -0.2794 0.1778)
							(mid -0.249642 0.249642)
							(end -0.1778 0.2794)
						)
						(arc
							(start 0.1778 0.2794)
							(mid 0.249642 0.249642)
							(end 0.2794 0.1778)
						)
						(arc
							(start 0.2794 -0.1778)
							(mid 0.249642 -0.249642)
							(end 0.1778 -0.2794)
						)
					)
					(width 0)
					(fill yes)
				)
			)
		)
	)
)
